FILE_TYPE = CONNECTIVITY;
{Allegro Design Entry HDL 17.2-2016 S081 (4005846) 1/11/2022}
"PAGE_NUMBER" = 162;
0"NC";
1"P3V3_AUX\g";
2"P3V3_AUX\g";
3"P3V3_AUX\g";
4"P3V3_AUX\g";
5"P3V3_AUX\g";
6"P3V3_AUX\g";
7"GND\g";
8"GND\g";
9"GND\g";
10"GND\g";
11"GND\g";
12"GND\g";
13"GND\g";
14"GND\g";
15"GND\g";
16"GND\g";
17"GND\g";
18"GND\g";
19"FM_USB3_1_RXDET_EN";
20"FM_USB3_1_EN_N";
21"USB3_PCH_TX_BUF_C_DP<4>";
22"USB3_PCH_TX_BUF_C_DN<4>";
23"USB3_PCH_RX_BUF_DP<4>";
24"USB3_PCH_RX_BUF_DN<4>";
25"FM_USB3_1_SWA";
26"FM_USB3_1_RXDET_EN";
27"FM_USB3_1_EN_N";
28"USB3_PCH_TX_BUF_DP<4>";
29"USB3_PCH_TX_BUF_DN<4>";
30"USB3_PCH_RX_BUF_C_DP<4>";
31"USB3_PCH_RX_BUF_C_DN<4>";
32"P3V3_AUX_USB_BUF";
33"FM_USB3_1_SWB";
34"USB3_PCH_RX_C_DN<4>";
35"USB3_PCH_RX_C_DP<4>";
36"FM_USB3_1_FGA";
37"FM_USB3_1_FGB";
38"FM_USB3_1_SWA";
39"FM_USB3_1_SWB";
40"FM_USB3_1_EQA";
41"FM_USB3_1_EQB";
42"USB3_PCH_TX_C_DP<4>";
43"USB3_PCH_TX_C_DN<4>";
44"FM_USB3_1_FGA";
45"USB3_PCH_RX_DN<4>";
46"USB3_PCH_RX_DP<4>";
47"FM_USB3_1_FGB";
48"FM_USB3_1_EQB";
49"FM_USB3_1_EQA";
%"UNIVERSAL_GND"
"1","(-5025,-1000)","0","logical_power","I1";
;
CDS_LIB"logical_power"
HDL_POWER"GND"
ROOM"IO_SLOT";
"A"7;
%"UNIVERSAL_GND"
"1","(-5350,750)","0","logical_power","I10";
;
CDS_LIB"logical_power"
HDL_POWER"GND"
ROOM"IO_SLOT";
"A"9;
%"Q_RES"
"2","(-5350,1100)","0","pure_quanta","I11";
;
PART_NUMBER"CS21002FB06"
MATERIAL"EMPTY"
TOLERANCE"1%"
WATTAGE"1/16W"
VALUE"1K"
PACK_TYPE"0402LF"
$LOCATION"R4274"
CDS_LIB"pure_quanta"
CDS_LOCATION"R4274"
$SEC"1"
CDS_SEC"1";
"A"
$PN"1"47;
"B"
$PN"2"9;
%"Q_RES"
"2","(-5350,1625)","0","pure_quanta","I12";
;
PART_NUMBER"CS21002FB06"
WATTAGE"1/16W"
TOLERANCE"1%"
VALUE"1K"
PACK_TYPE"0402LF"
MATERIAL"EMPTY"
$LOCATION"R4273"
CDS_LIB"pure_quanta"
CDS_LOCATION"R4273"
$SEC"1"
CDS_SEC"1";
"A"
$PN"1"2;
"B"
$PN"2"47;
%"UNIVERSAL_POWER"
"1","(-5350,1925)","0","logical_power","I13";
;
HDL_POWER"P3V3_AUX"
CDS_LIB"logical_power";
"A"2;
%"UNIVERSAL_GND"
"1","(-4475,750)","0","logical_power","I16";
;
CDS_LIB"logical_power"
ROOM"IO_SLOT"
HDL_POWER"GND";
"A"10;
%"Q_RES"
"2","(-4475,1050)","0","pure_quanta","I17";
;
PART_NUMBER"CS21002FB06"
PACK_TYPE"0402LF"
MATERIAL"EMPTY"
WATTAGE"1/16W"
TOLERANCE"1%"
VALUE"1K"
$LOCATION"R4280"
CDS_LIB"pure_quanta"
CDS_LOCATION"R4280"
$SEC"1"
CDS_SEC"1";
"A"
$PN"1"44;
"B"
$PN"2"10;
%"Q_RES"
"2","(-4475,1625)","0","pure_quanta","I18";
;
PART_NUMBER"CS21002FB06"
WATTAGE"1/16W"
PACK_TYPE"0402LF"
VALUE"1K"
TOLERANCE"1%"
MATERIAL"EMPTY"
$LOCATION"R4279"
CDS_LIB"pure_quanta"
CDS_LOCATION"R4279"
$SEC"1"
CDS_SEC"1";
"A"
$PN"1"2;
"B"
$PN"2"44;
%"Q_RES"
"2","(-5025,-650)","0","pure_quanta","I2";
;
PART_NUMBER"CS36802FB04"
VALUE"68K"
TOLERANCE"1%"
PACK_TYPE"0402LF"
MATERIAL"CHIP"
WATTAGE"1/16W"
LOCATION"R4276"
CDS_LIB"pure_quanta"
$SEC"1"
CDS_SEC"1";
"A"
$PN"1"49;
"B"
$PN"2"7;
%"UNIVERSAL_GND"
"1","(-3850,2600)","0","logical_power","I21";
;
HDL_POWER"GND"
ROOM"IO_SLOT"
CDS_LIB"logical_power";
"A"11;
%"UNIVERSAL_GND"
"1","(-4250,2600)","0","logical_power","I22";
;
CDS_LIB"logical_power"
HDL_POWER"GND"
ROOM"IO_SLOT";
"A"12;
%"Q_RES"
"2","(-4250,2900)","0","pure_quanta","I23";
;
PART_NUMBER"CS42002FB05"
MATERIAL"CHIP"
PACK_TYPE"0402LF"
VALUE"200K"
WATTAGE"1/16W"
TOLERANCE"1%"
$LOCATION"R4636"
CDS_LIB"pure_quanta"
CDS_LOCATION"R4636"
$SEC"1"
CDS_SEC"1";
"A"
$PN"1"46;
"B"
$PN"2"12;
%"Q_RES"
"2","(-3850,2900)","0","pure_quanta","I24";
;
PART_NUMBER"CS42002FB05"
PACK_TYPE"0402LF"
TOLERANCE"1%"
VALUE"200K"
WATTAGE"1/16W"
MATERIAL"CHIP"
$LOCATION"R4637"
CDS_LIB"pure_quanta"
CDS_LOCATION"R4637"
$SEC"1"
CDS_SEC"1";
"A"
$PN"1"45;
"B"
$PN"2"11;
%"Q_CAP_DIFFBUS"
"2","(-3725,3175)","0","pure_quanta","I25";
;
PART_NUMBER"SP_CH4331KEB01"
PACK_TYPE"C0402"
TOLERANCE"10%"
VALUE"DIFF BUS_0.33UF"
LOCATION"C2350"
VOLTAGE"6.3V"
MATERIAL"X6S"
CDS_LMAN_SYM_OUTLINE"-25,50,25,-50"
PIN_NAMES_ROTATE"True"
CDS_LIB"pure_quanta"
$SEC"1"
CDS_SEC"1";
"2"
$PN"2"34;
"1"
$PN"1"45;
%"Q_CAP_DIFFBUS"
"2","(-3725,3225)","0","pure_quanta","I26";
;
PART_NUMBER"SP_CH4331KEB01"
VALUE"DIFF BUS_0.33UF"
TOLERANCE"10%"
PACK_TYPE"C0402"
LOCATION"C2349"
CDS_LIB"pure_quanta"
CDS_LMAN_SYM_OUTLINE"-25,50,25,-50"
VOLTAGE"6.3V"
MATERIAL"X6S"
PIN_NAMES_ROTATE"True"
$SEC"1"
CDS_SEC"1";
"2"
$PN"2"35;
"1"
$PN"1"46;
%"Q_RES"
"2","(-5025,-125)","0","pure_quanta","I3";
;
PART_NUMBER"CS21002FB06"
MATERIAL"EMPTY"
VALUE"1K"
TOLERANCE"1%"
WATTAGE"1/16W"
PACK_TYPE"0402LF"
$LOCATION"R4275"
CDS_LIB"pure_quanta"
CDS_LOCATION"R4275"
$SEC"1"
CDS_SEC"1";
"A"
$PN"1"1;
"B"
$PN"2"49;
%"Q_INDUCTOR"
"1","(-3300,4650)","0","pure_quanta","I35";
;
PART_NUMBER"CX5PX121001"
MATERIAL"IND"
VALUE"BLM15PX121SN1D/2A"
PACK_TYPE"SMLF"
$LOCATION"L18"
CDS_LIB"pure_quanta"
NEEDS_NO_SIZE"TRUE"
CDS_LOCATION"L18"
$SEC"1"
CDS_SEC"1";
"1"
$PN"1"3;
"2"
$PN"2"32;
%"UNIVERSAL_GND"
"1","(-3025,4025)","0","logical_power","I36";
;
CDS_LIB"logical_power"
HDL_POWER"GND";
"A"13;
%"Q_CAP"
"1","(-3025,4375)","0","pure_quanta","I37";
;
PART_NUMBER"CH6223MEA00"
MATERIAL"X6S"
VOLTAGE"16V"
VALUE"22UF"
PACK_TYPE"C0805"
TOLERANCE"20%"
LOCATION"C2284"
CDS_LIB"pure_quanta"
$SEC"1"
CDS_SEC"1";
"B"
$PN"2"13;
"A"
$PN"1"32;
%"UNIVERSAL_POWER"
"1","(-3650,4800)","0","logical_power","I38";
;
HDL_POWER"P3V3_AUX"
CDS_LIB"logical_power";
"A"3;
%"UNIVERSAL_GND"
"1","(-750,725)","0","logical_power","I39";
;
CDS_LIB"logical_power"
HDL_POWER"GND"
ROOM"IO_SLOT";
"A"14;
%"UNIVERSAL_POWER"
"1","(-5025,175)","0","logical_power","I4";
;
HDL_POWER"P3V3_AUX"
CDS_LIB"logical_power";
"A"1;
%"Q_RES"
"2","(-750,1075)","0","pure_quanta","I40";
;
PART_NUMBER"CS21002FB06"
VALUE"1K"
PACK_TYPE"0402LF"
MATERIAL"EMPTY"
TOLERANCE"1%"
WATTAGE"1/16W"
$LOCATION"R4285"
CDS_LIB"pure_quanta"
CDS_LOCATION"R4285"
$SEC"1"
CDS_SEC"1";
"A"
$PN"1"33;
"B"
$PN"2"14;
%"Q_RES"
"2","(-750,1600)","0","pure_quanta","I41";
;
PART_NUMBER"CS21002FB06"
PACK_TYPE"0402LF"
MATERIAL"EMPTY"
VALUE"1K"
WATTAGE"1/16W"
TOLERANCE"1%"
$LOCATION"R4284"
CDS_LIB"pure_quanta"
CDS_LOCATION"R4284"
$SEC"1"
CDS_SEC"1";
"A"
$PN"1"4;
"B"
$PN"2"33;
%"UNIVERSAL_POWER"
"1","(-750,1900)","0","logical_power","I42";
;
HDL_POWER"P3V3_AUX"
CDS_LIB"logical_power";
"A"4;
%"PI3EQX1002EZREX"
"1","(-1550,3550)","0","pure_quanta","I43";
;
PART_NUMBER"AL001002007"
MATERIAL"IC"
PART_TYPE"SMLF"
VALUE"PI3EQX1002EZREX"
LOCATION"U309"
CDS_LMAN_SYM_OUTLINE"-300,625,300,-625"
NEEDS_NO_SIZE"TRUE"
CDS_LIB"pure_quanta"
$SEC"1"
CDS_SEC"1";
"GND_4"
$PN"20"15;
"BOP"
$PN"12"30;
"BON"
$PN"11"31;
"GND_5"
$PN"21"15;
"GND_3"
$PN"10"15;
"EQB"
$PN"16"41;
"GND_1"
$PN"8"15;
"SWA"
$PN"3"38;
"BIP"
$PN"18"35;
"SWB"
$PN"14"39;
"BIN"
$PN"19"34;
"FGB"
$PN"15"37;
"TH_GND"
$PN"TH"15;
"AIP"
$PN"6"42;
"RXDET_EN"
$PN"13"26;
"FGA"
$PN"2"36;
"EQA"
$PN"1"40;
"AIN"
$PN"7"43;
"GND_6"
$PN"22"15;
"AOP"
$PN"24"28;
"AON"
$PN"23"29;
"VDD_1"
$PN"5"32;
"EN"
$PN"4"27;
"VDD_2"
$PN"17"32;
"GND_2"
$PN"9"15;
%"Q_CAP"
"1","(-2650,4375)","0","pure_quanta","I44";
;
PART_NUMBER"CH4104K1B00"
PACK_TYPE"0402"
TOLERANCE"10%"
MATERIAL"X7R"
VOLTAGE"25V"
VALUE"0.1UF"
$LOCATION"C2285"
CDS_LIB"pure_quanta"
CDS_LOCATION"C2285"
$SEC"1"
CDS_SEC"1";
"B"
$PN"2"13;
"A"
$PN"1"32;
%"Q_CAP"
"1","(-2375,4375)","0","pure_quanta","I45";
;
PART_NUMBER"CH4104K1B00"
TOLERANCE"10%"
VOLTAGE"25V"
VALUE"0.1UF"
MATERIAL"X7R"
PACK_TYPE"0402"
$LOCATION"C2286"
CDS_LIB"pure_quanta"
CDS_LOCATION"C2286"
$SEC"1"
CDS_SEC"1";
"B"
$PN"2"13;
"A"
$PN"1"32;
%"UNIVERSAL_GND"
"1","(-1025,2775)","0","logical_power","I46";
;
CDS_LIB"logical_power"
HDL_POWER"GND";
"A"15;
%"UNIVERSAL_GND"
"1","(125,725)","0","logical_power","I47";
;
CDS_LIB"logical_power"
HDL_POWER"GND"
ROOM"IO_SLOT";
"A"16;
%"Q_RES"
"2","(125,1025)","0","pure_quanta","I48";
;
PART_NUMBER"CS21002FB06"
TOLERANCE"1%"
VALUE"1K"
WATTAGE"1/16W"
MATERIAL"EMPTY"
PACK_TYPE"0402LF"
$LOCATION"R4288"
CDS_LIB"pure_quanta"
CDS_LOCATION"R4288"
$SEC"1"
CDS_SEC"1";
"A"
$PN"1"25;
"B"
$PN"2"16;
%"Q_RES"
"2","(125,1600)","0","pure_quanta","I49";
;
PART_NUMBER"CS21002FB06"
WATTAGE"1/16W"
VALUE"1K"
TOLERANCE"1%"
MATERIAL"EMPTY"
PACK_TYPE"0402LF"
$LOCATION"R4287"
CDS_LIB"pure_quanta"
CDS_LOCATION"R4287"
$SEC"1"
CDS_SEC"1";
"A"
$PN"1"4;
"B"
$PN"2"25;
%"UNIVERSAL_GND"
"1","(-4150,-1000)","0","logical_power","I5";
;
CDS_LIB"logical_power"
HDL_POWER"GND"
ROOM"IO_SLOT";
"A"8;
%"Q_CAP"
"2","(0,3825)","0","pure_quanta","I54";
;
PART_NUMBER"CH4101KEE01"
MATERIAL"X6S"
VALUE"0.1UF"
$LOCATION"C2292"
CDS_LIB"pure_quanta"
PACK_TYPE"C0201"
TOLERANCE"10%"
VOLTAGE"6.3V"
CDS_LOCATION"C2292"
$SEC"1"
CDS_SEC"1";
"A"
$PN"1"31;
"B"
$PN"2"24;
%"Q_CAP"
"2","(0,3875)","0","pure_quanta","I55";
;
PART_NUMBER"CH4101KEE01"
MATERIAL"X6S"
VALUE"0.1UF"
$LOCATION"C2291"
CDS_LIB"pure_quanta"
PACK_TYPE"C0201"
TOLERANCE"10%"
VOLTAGE"6.3V"
CDS_LOCATION"C2291"
$SEC"1"
CDS_SEC"1";
"A"
$PN"1"30;
"B"
$PN"2"23;
%"Q_CAP"
"2","(0,4025)","0","pure_quanta","I56";
;
PART_NUMBER"CH4101KEE01"
MATERIAL"X6S"
VALUE"0.1UF"
$LOCATION"C2290"
VOLTAGE"6.3V"
TOLERANCE"10%"
PACK_TYPE"C0201"
CDS_LIB"pure_quanta"
CDS_LOCATION"C2290"
$SEC"1"
CDS_SEC"1";
"A"
$PN"1"29;
"B"
$PN"2"22;
%"Q_CAP"
"2","(0,4075)","0","pure_quanta","I57";
;
PART_NUMBER"CH4101KEE01"
VALUE"0.1UF"
MATERIAL"X6S"
TOLERANCE"10%"
PACK_TYPE"C0201"
VOLTAGE"6.3V"
$LOCATION"C2289"
CDS_LIB"pure_quanta"
CDS_LOCATION"C2289"
$SEC"1"
CDS_SEC"1";
"A"
$PN"1"28;
"B"
$PN"2"21;
%"Q_RES"
"2","(-4150,-700)","0","pure_quanta","I6";
;
PART_NUMBER"CS36802FB04"
PACK_TYPE"0402LF"
VALUE"68K"
TOLERANCE"1%"
WATTAGE"1/16W"
MATERIAL"CHIP"
LOCATION"R4282"
CDS_LIB"pure_quanta"
$SEC"1"
CDS_SEC"1";
"A"
$PN"1"48;
"B"
$PN"2"8;
%"UNIVERSAL_GND"
"1","(2000,2050)","0","logical_power","I62";
;
CDS_LIB"logical_power"
HDL_POWER"GND"
ROOM"IO_SLOT";
"A"17;
%"Q_RES"
"2","(2000,2275)","0","pure_quanta","I63";
;
PART_NUMBER"CS24702FB06"
MATERIAL"EMPTY"
WATTAGE"1/16W"
VALUE"4.7K"
TOLERANCE"1%"
PACK_TYPE"0402LF"
$LOCATION"R4292"
CDS_LIB"pure_quanta"
CDS_LOCATION"R4292"
$SEC"1"
CDS_SEC"1";
"A"
$PN"1"20;
"B"
$PN"2"17;
%"Q_RES"
"2","(2000,2800)","0","pure_quanta","I65";
;
PART_NUMBER"CS24702FB06"
PACK_TYPE"0402LF"
TOLERANCE"1%"
VALUE"4.7K"
MATERIAL"EMPTY"
WATTAGE"1/16W"
$LOCATION"R4291"
CDS_LIB"pure_quanta"
CDS_LOCATION"R4291"
$SEC"1"
CDS_SEC"1";
"A"
$PN"1"5;
"B"
$PN"2"20;
%"UNIVERSAL_POWER"
"1","(2000,3100)","0","logical_power","I66";
;
HDL_POWER"P3V3_AUX"
CDS_LIB"logical_power";
"A"5;
%"UNIVERSAL_GND"
"1","(2000,3425)","0","logical_power","I67";
;
CDS_LIB"logical_power"
HDL_POWER"GND"
ROOM"IO_SLOT";
"A"18;
%"Q_RES"
"2","(2000,3650)","0","pure_quanta","I68";
;
PART_NUMBER"CS24702FB06"
MATERIAL"EMPTY"
PACK_TYPE"0402LF"
WATTAGE"1/16W"
VALUE"4.7K"
TOLERANCE"1%"
$LOCATION"R4290"
CDS_LIB"pure_quanta"
CDS_LOCATION"R4290"
$SEC"1"
CDS_SEC"1";
"A"
$PN"1"19;
"B"
$PN"2"18;
%"Q_RES"
"2","(2000,4175)","0","pure_quanta","I69";
;
PART_NUMBER"CS24702FB06"
MATERIAL"EMPTY"
PACK_TYPE"0402LF"
WATTAGE"1/16W"
TOLERANCE"1%"
VALUE"4.7K"
$LOCATION"R4289"
CDS_LIB"pure_quanta"
CDS_LOCATION"R4289"
$SEC"1"
CDS_SEC"1";
"A"
$PN"1"6;
"B"
$PN"2"19;
%"Q_RES"
"2","(-4150,-125)","0","pure_quanta","I7";
;
PART_NUMBER"CS21002FB06"
WATTAGE"1/16W"
TOLERANCE"1%"
VALUE"1K"
MATERIAL"EMPTY"
PACK_TYPE"0402LF"
$LOCATION"R4281"
CDS_LIB"pure_quanta"
CDS_LOCATION"R4281"
$SEC"1"
CDS_SEC"1";
"A"
$PN"1"1;
"B"
$PN"2"48;
%"UNIVERSAL_POWER"
"1","(2000,4475)","0","logical_power","I70";
;
HDL_POWER"P3V3_AUX"
CDS_LIB"logical_power";
"A"6;
END.
